(kicad_pcb
	(version 20260206)
	(generator "pcbnew")
	(generator_version "10.0")
	(general
		(thickness 1.6)
		(legacy_teardrops no)
	)
	(paper "A4")
	(title_block
		(title "peb — Lightning_PEB_BRD.brd")
		(comment 1 "Lightning (Wiwynn / Facebook NVMe JBOF) / footprints 2005-2012 of 2563")
	)
	(layers
		(0 "F.Cu" signal "TOP")
		(4 "In1.Cu" signal "L2GND")
		(6 "In2.Cu" signal "L3")
		(8 "In3.Cu" signal "L4VCC")
		(10 "In4.Cu" signal "L5VCC")
		(12 "In5.Cu" signal "L6")
		(14 "In6.Cu" signal "L7GND")
		(2 "B.Cu" signal "BOTTOM")
		(9 "F.Adhes" user "F.Adhesive")
		(11 "B.Adhes" user "B.Adhesive")
		(13 "F.Paste" user "Package Geometry/Pastemask Top")
		(15 "B.Paste" user "Package Geometry/Pastemask Bottom")
		(5 "F.SilkS" user "Ref Des/Silkscreen Top")
		(7 "B.SilkS" user "Ref Des/Silkscreen Bottom")
		(1 "F.Mask" user "Board Geometry/Soldermask Top")
		(3 "B.Mask" user "Board Geometry/Soldermask Bottom")
		(17 "Dwgs.User" user "User.Drawings")
		(19 "Cmts.User" user "User.Comments")
		(21 "Eco1.User" user "User.Eco1")
		(23 "Eco2.User" user "User.Eco2")
		(25 "Edge.Cuts" user "Board Geometry/Outline")
		(27 "Margin" user)
		(31 "F.CrtYd" user "Package Geometry/Place Bound Top")
		(29 "B.CrtYd" user "Package Geometry/Place Bound Bottom")
		(35 "F.Fab" user "Ref Des/Assembly Top")
		(33 "B.Fab" user "Ref Des/Assembly Bottom")
	)
	(footprint ""
		(layer "B.Cu")
		(at 263.139174 -0.721868 90)
		(property "Reference" "R203"
			(at 0 0 90)
			(layer "B.SilkS")
			(hide yes)
			(effects
				(font
					(size 1.27 1.27)
				)
				(justify mirror)
			)
		)
		(property "Value" "0R2J-2-GP"
			(at -0.064008 -3.993896 90)
			(unlocked yes)
			(layer "B.Fab")
			(hide yes)
			(effects
				(font
					(size 1.016 1.016)
					(thickness 0.1524)
				)
				(justify mirror)
			)
		)
		(property "Device Type" "R402H16"
			(at -0.064008 -5.517896 90)
			(unlocked yes)
			(layer "B.Fab")
			(hide yes)
			(effects
				(font
					(size 1.016 1.016)
					(thickness 0.1524)
				)
				(justify mirror)
			)
		)
		(duplicate_pad_numbers_are_jumpers no)
		(fp_line
			(start 0.508 -0.9398)
			(end 0.508 0.9398)
			(stroke
				(width 0.1524)
				(type default)
			)
			(layer "B.SilkS")
		)
		(fp_line
			(start -0.508 -0.9398)
			(end 0.508 -0.9398)
			(stroke
				(width 0.1524)
				(type default)
			)
			(layer "B.SilkS")
		)
		(fp_rect
			(start 0.508 0.9398)
			(end -0.508 -0.9398)
			(stroke
				(width 0)
				(type default)
			)
			(fill no)
			(layer "B.CrtYd")
		)
		(fp_rect
			(start 0.508 0.9398)
			(end -0.508 -0.9398)
			(stroke
				(width 0)
				(type default)
			)
			(fill no)
			(layer "B.Fab")
		)
		(pad "1" smd custom
			(at 0 -0.4445 270)
			(size 0.1397 0.1397)
			(layers "B.Cu" "B.Mask" "B.Paste")
			(net "GND")
			(options
				(clearance outline)
				(anchor circle)
			)
			(primitives
				(gr_poly
					(pts
						(arc
							(start -0.1778 0.2794)
							(mid -0.249642 0.249642)
							(end -0.2794 0.1778)
						)
						(arc
							(start -0.2794 -0.1778)
							(mid -0.249642 -0.249642)
							(end -0.1778 -0.2794)
						)
						(arc
							(start 0.1778 -0.2794)
							(mid 0.249642 -0.249642)
							(end 0.2794 -0.1778)
						)
						(arc
							(start 0.2794 0.1778)
							(mid 0.249642 0.249642)
							(end 0.1778 0.2794)
						)
					)
					(width 0)
					(fill yes)
				)
			)
		)
		(pad "2" smd custom
			(at 0 0.4445 270)
			(size 0.1397 0.1397)
			(layers "B.Cu" "B.Mask" "B.Paste")
			(net "TEMP_SENSOR_C")
			(options
				(clearance outline)
				(anchor circle)
			)
			(primitives
				(gr_poly
					(pts
						(arc
							(start -0.1778 0.2794)
							(mid -0.249642 0.249642)
							(end -0.2794 0.1778)
						)
						(arc
							(start -0.2794 -0.1778)
							(mid -0.249642 -0.249642)
							(end -0.1778 -0.2794)
						)
						(arc
							(start 0.1778 -0.2794)
							(mid 0.249642 -0.249642)
							(end 0.2794 -0.1778)
						)
						(arc
							(start 0.2794 0.1778)
							(mid 0.249642 0.249642)
							(end 0.1778 0.2794)
						)
					)
					(width 0)
					(fill yes)
				)
			)
		)
	)
	(footprint ""
		(layer "B.Cu")
		(at 238.6076 -36.9824 180)
		(property "Reference" "R8"
			(at 0 0 0)
			(layer "B.SilkS")
			(hide yes)
			(effects
				(font
					(size 1.27 1.27)
				)
				(justify mirror)
			)
		)
		(property "Value" "33R1J-GP"
			(at 3.3274 -1.3335 180)
			(unlocked yes)
			(layer "B.Fab")
			(hide yes)
			(effects
				(font
					(size 1.016 1.016)
					(thickness 0.1524)
				)
				(justify mirror)
			)
		)
		(property "Device Type" "R0201H12"
			(at 3.3274 -2.8575 180)
			(unlocked yes)
			(layer "B.Fab")
			(hide yes)
			(effects
				(font
					(size 1.016 1.016)
					(thickness 0.1524)
				)
				(justify mirror)
			)
		)
		(duplicate_pad_numbers_are_jumpers no)
		(fp_rect
			(start 0.2794 0.6477)
			(end -0.2794 -0.6477)
			(stroke
				(width 0)
				(type default)
			)
			(fill no)
			(layer "B.CrtYd")
		)
		(fp_rect
			(start 0.2794 0.6477)
			(end -0.2794 -0.6477)
			(stroke
				(width 0)
				(type default)
			)
			(fill no)
			(layer "B.Fab")
		)
		(pad "1" smd custom
			(at 0 -0.2794)
			(size 0.0762 0.0762)
			(layers "B.Cu" "B.Mask" "B.Paste")
			(net "PCIE_REFCLK_H2_N")
			(options
				(clearance outline)
				(anchor circle)
			)
			(primitives
				(gr_poly
					(pts
						(arc
							(start 0.1524 0.127)
							(mid 0.137521 0.162921)
							(end 0.1016 0.1778)
						)
						(arc
							(start -0.1016 0.1778)
							(mid -0.137521 0.162921)
							(end -0.1524 0.127)
						)
						(arc
							(start -0.1524 -0.127)
							(mid -0.137521 -0.162921)
							(end -0.1016 -0.1778)
						)
						(arc
							(start 0.1016 -0.1778)
							(mid 0.137521 -0.162921)
							(end 0.1524 -0.127)
						)
					)
					(width 0)
					(fill yes)
				)
			)
		)
		(pad "2" smd custom
			(at 0 0.2794)
			(size 0.0762 0.0762)
			(layers "B.Cu" "B.Mask" "B.Paste")
			(net "PCIE_REFCLK_H2_P")
			(options
				(clearance outline)
				(anchor circle)
			)
			(primitives
				(gr_poly
					(pts
						(arc
							(start 0.1524 0.127)
							(mid 0.137521 0.162921)
							(end 0.1016 0.1778)
						)
						(arc
							(start -0.1016 0.1778)
							(mid -0.137521 0.162921)
							(end -0.1524 0.127)
						)
						(arc
							(start -0.1524 -0.127)
							(mid -0.137521 -0.162921)
							(end -0.1016 -0.1778)
						)
						(arc
							(start 0.1016 -0.1778)
							(mid 0.137521 -0.162921)
							(end 0.1524 -0.127)
						)
					)
					(width 0)
					(fill yes)
				)
			)
		)
	)
	(footprint ""
		(layer "B.Cu")
		(at 247.1166 -47.032672 -90)
		(property "Reference" "C452"
			(at 0 0 90)
			(layer "B.SilkS")
			(hide yes)
			(effects
				(font
					(size 1.27 1.27)
				)
				(justify mirror)
			)
		)
		(property "Value" "SCD1U16V1KX-1-GP"
			(at 2.8321 -1.7399 270)
			(unlocked yes)
			(layer "B.Fab")
			(hide yes)
			(effects
				(font
					(size 1.016 1.016)
					(thickness 0.1524)
				)
				(justify mirror)
			)
		)
		(property "Device Type" "C0201H13"
			(at 2.8321 -3.2639 270)
			(unlocked yes)
			(layer "B.Fab")
			(hide yes)
			(effects
				(font
					(size 1.016 1.016)
					(thickness 0.1524)
				)
				(justify mirror)
			)
		)
		(duplicate_pad_numbers_are_jumpers no)
		(fp_rect
			(start 0.2794 0.6477)
			(end -0.2794 -0.6477)
			(stroke
				(width 0)
				(type default)
			)
			(fill no)
			(layer "B.CrtYd")
		)
		(fp_rect
			(start 0.2794 0.6477)
			(end -0.2794 -0.6477)
			(stroke
				(width 0)
				(type default)
			)
			(fill no)
			(layer "B.Fab")
		)
		(pad "1" smd custom
			(at 0 -0.2794 90)
			(size 0.0762 0.0762)
			(layers "B.Cu" "B.Mask" "B.Paste")
			(net "DUT_VDD")
			(options
				(clearance outline)
				(anchor circle)
			)
			(primitives
				(gr_poly
					(pts
						(arc
							(start 0.1524 0.127)
							(mid 0.137521 0.162921)
							(end 0.1016 0.1778)
						)
						(arc
							(start -0.1016 0.1778)
							(mid -0.137521 0.162921)
							(end -0.1524 0.127)
						)
						(arc
							(start -0.1524 -0.127)
							(mid -0.137521 -0.162921)
							(end -0.1016 -0.1778)
						)
						(arc
							(start 0.1016 -0.1778)
							(mid 0.137521 -0.162921)
							(end 0.1524 -0.127)
						)
					)
					(width 0)
					(fill yes)
				)
			)
		)
		(pad "2" smd custom
			(at 0 0.2794 90)
			(size 0.0762 0.0762)
			(layers "B.Cu" "B.Mask" "B.Paste")
			(net "GND")
			(options
				(clearance outline)
				(anchor circle)
			)
			(primitives
				(gr_poly
					(pts
						(arc
							(start 0.1524 0.127)
							(mid 0.137521 0.162921)
							(end 0.1016 0.1778)
						)
						(arc
							(start -0.1016 0.1778)
							(mid -0.137521 0.162921)
							(end -0.1524 0.127)
						)
						(arc
							(start -0.1524 -0.127)
							(mid -0.137521 -0.162921)
							(end -0.1016 -0.1778)
						)
						(arc
							(start 0.1016 -0.1778)
							(mid 0.137521 -0.162921)
							(end 0.1524 -0.127)
						)
					)
					(width 0)
					(fill yes)
				)
			)
		)
	)
	(footprint ""
		(layer "B.Cu")
		(at 313.436 -55.372)
		(property "Reference" "PC178"
			(at 0 0 0)
			(layer "B.SilkS")
			(hide yes)
			(effects
				(font
					(size 1.27 1.27)
				)
				(justify mirror)
			)
		)
		(property "Value" "SC22U6D3V5MX-5-GP"
			(at 0.0762 -6.1214 0)
			(unlocked yes)
			(layer "B.Fab")
			(hide yes)
			(effects
				(font
					(size 1.016 1.016)
					(thickness 0.1524)
				)
				(justify mirror)
			)
		)
		(property "Device Type" "C805H56"
			(at 0.0762 -8.1534 0)
			(unlocked yes)
			(layer "B.Fab")
			(hide yes)
			(effects
				(font
					(size 1.016 1.016)
					(thickness 0.1524)
				)
				(justify mirror)
			)
		)
		(duplicate_pad_numbers_are_jumpers no)
		(fp_line
			(start -0.635 0)
			(end 0.635 0)
			(stroke
				(width 0.508)
				(type default)
			)
			(layer "B.SilkS")
		)
		(fp_rect
			(start 0.9652 1.778)
			(end -0.9652 -1.778)
			(stroke
				(width 0)
				(type default)
			)
			(fill no)
			(layer "B.CrtYd")
		)
		(fp_poly
			(pts
				(xy 0.9652 -1.778) (xy -0.9652 -1.778) (xy -0.9652 1.778) (xy 0.9652 1.778)
			)
			(stroke
				(width 0)
				(type default)
			)
			(fill no)
			(layer "B.Fab")
		)
		(pad "1" smd rect
			(at 0 -0.9652 180)
			(size 1.397 1.143)
			(layers "B.Cu" "B.Mask" "B.Paste")
			(net "P0V9_E")
		)
		(pad "2" smd rect
			(at 0 0.9652 180)
			(size 1.397 1.143)
			(layers "B.Cu" "B.Mask" "B.Paste")
			(net "GND")
		)
	)
	(footprint ""
		(layer "B.Cu")
		(at 220.956124 -203.047092 180)
		(property "Reference" "R4149"
			(at 0 0 0)
			(layer "B.SilkS")
			(hide yes)
			(effects
				(font
					(size 1.27 1.27)
				)
				(justify mirror)
			)
		)
		(property "Value" "4K7R2F-GP"
			(at -0.064008 -3.993896 180)
			(unlocked yes)
			(layer "B.Fab")
			(hide yes)
			(effects
				(font
					(size 1.016 1.016)
					(thickness 0.1524)
				)
				(justify mirror)
			)
		)
		(property "Device Type" "R402H16"
			(at -0.064008 -5.517896 180)
			(unlocked yes)
			(layer "B.Fab")
			(hide yes)
			(effects
				(font
					(size 1.016 1.016)
					(thickness 0.1524)
				)
				(justify mirror)
			)
		)
		(duplicate_pad_numbers_are_jumpers no)
		(fp_line
			(start 0.508 -0.9398)
			(end 0.508 0.9398)
			(stroke
				(width 0.1524)
				(type default)
			)
			(layer "B.SilkS")
		)
		(fp_line
			(start -0.508 -0.9398)
			(end 0.508 -0.9398)
			(stroke
				(width 0.1524)
				(type default)
			)
			(layer "B.SilkS")
		)
		(fp_rect
			(start 0.508 0.9398)
			(end -0.508 -0.9398)
			(stroke
				(width 0)
				(type default)
			)
			(fill no)
			(layer "B.CrtYd")
		)
		(fp_rect
			(start 0.508 0.9398)
			(end -0.508 -0.9398)
			(stroke
				(width 0)
				(type default)
			)
			(fill no)
			(layer "B.Fab")
		)
		(pad "1" smd custom
			(at 0 -0.4445)
			(size 0.1397 0.1397)
			(layers "B.Cu" "B.Mask" "B.Paste")
			(net "SSD_PERST#13")
			(options
				(clearance outline)
				(anchor circle)
			)
			(primitives
				(gr_poly
					(pts
						(arc
							(start -0.1778 0.2794)
							(mid -0.249642 0.249642)
							(end -0.2794 0.1778)
						)
						(arc
							(start -0.2794 -0.1778)
							(mid -0.249642 -0.249642)
							(end -0.1778 -0.2794)
						)
						(arc
							(start 0.1778 -0.2794)
							(mid 0.249642 -0.249642)
							(end 0.2794 -0.1778)
						)
						(arc
							(start 0.2794 0.1778)
							(mid 0.249642 0.249642)
							(end 0.1778 0.2794)
						)
					)
					(width 0)
					(fill yes)
				)
			)
		)
		(pad "2" smd custom
			(at 0 0.4445)
			(size 0.1397 0.1397)
			(layers "B.Cu" "B.Mask" "B.Paste")
			(net "P3V3_STBY")
			(options
				(clearance outline)
				(anchor circle)
			)
			(primitives
				(gr_poly
					(pts
						(arc
							(start -0.1778 0.2794)
							(mid -0.249642 0.249642)
							(end -0.2794 0.1778)
						)
						(arc
							(start -0.2794 -0.1778)
							(mid -0.249642 -0.249642)
							(end -0.1778 -0.2794)
						)
						(arc
							(start 0.1778 -0.2794)
							(mid 0.249642 -0.249642)
							(end 0.2794 -0.1778)
						)
						(arc
							(start 0.2794 0.1778)
							(mid 0.249642 0.249642)
							(end 0.1778 0.2794)
						)
					)
					(width 0)
					(fill yes)
				)
			)
		)
	)
	(footprint ""
		(layer "B.Cu")
		(at 272.6055 -9.7155)
		(property "Reference" "R388"
			(at 0 0 0)
			(layer "B.SilkS")
			(hide yes)
			(effects
				(font
					(size 1.27 1.27)
				)
				(justify mirror)
			)
		)
		(property "Value" "0R2J-2-GP"
			(at -0.064008 -3.993896 0)
			(unlocked yes)
			(layer "B.Fab")
			(hide yes)
			(effects
				(font
					(size 1.016 1.016)
					(thickness 0.1524)
				)
				(justify mirror)
			)
		)
		(property "Device Type" "R402H16"
			(at -0.064008 -5.517896 0)
			(unlocked yes)
			(layer "B.Fab")
			(hide yes)
			(effects
				(font
					(size 1.016 1.016)
					(thickness 0.1524)
				)
				(justify mirror)
			)
		)
		(duplicate_pad_numbers_are_jumpers no)
		(fp_line
			(start -0.508 -0.9398)
			(end 0.508 -0.9398)
			(stroke
				(width 0.1524)
				(type default)
			)
			(layer "B.SilkS")
		)
		(fp_line
			(start 0.508 -0.9398)
			(end 0.508 0.9398)
			(stroke
				(width 0.1524)
				(type default)
			)
			(layer "B.SilkS")
		)
		(fp_rect
			(start 0.508 0.9398)
			(end -0.508 -0.9398)
			(stroke
				(width 0)
				(type default)
			)
			(fill no)
			(layer "B.CrtYd")
		)
		(fp_rect
			(start 0.508 0.9398)
			(end -0.508 -0.9398)
			(stroke
				(width 0)
				(type default)
			)
			(fill no)
			(layer "B.Fab")
		)
		(pad "1" smd custom
			(at 0 -0.4445 180)
			(size 0.1397 0.1397)
			(layers "B.Cu" "B.Mask" "B.Paste")
			(net "CLK_P_5_R")
			(options
				(clearance outline)
				(anchor circle)
			)
			(primitives
				(gr_poly
					(pts
						(arc
							(start -0.1778 0.2794)
							(mid -0.249642 0.249642)
							(end -0.2794 0.1778)
						)
						(arc
							(start -0.2794 -0.1778)
							(mid -0.249642 -0.249642)
							(end -0.1778 -0.2794)
						)
						(arc
							(start 0.1778 -0.2794)
							(mid 0.249642 -0.249642)
							(end 0.2794 -0.1778)
						)
						(arc
							(start 0.2794 0.1778)
							(mid 0.249642 0.249642)
							(end 0.1778 0.2794)
						)
					)
					(width 0)
					(fill yes)
				)
			)
		)
		(pad "2" smd custom
			(at 0 0.4445 180)
			(size 0.1397 0.1397)
			(layers "B.Cu" "B.Mask" "B.Paste")
			(net "PCIE_REFCLK_H0_P_R")
			(options
				(clearance outline)
				(anchor circle)
			)
			(primitives
				(gr_poly
					(pts
						(arc
							(start -0.1778 0.2794)
							(mid -0.249642 0.249642)
							(end -0.2794 0.1778)
						)
						(arc
							(start -0.2794 -0.1778)
							(mid -0.249642 -0.249642)
							(end -0.1778 -0.2794)
						)
						(arc
							(start 0.1778 -0.2794)
							(mid 0.249642 -0.249642)
							(end 0.2794 -0.1778)
						)
						(arc
							(start 0.2794 0.1778)
							(mid 0.249642 0.249642)
							(end 0.1778 0.2794)
						)
					)
					(width 0)
					(fill yes)
				)
			)
		)
	)
	(footprint ""
		(layer "B.Cu")
		(at 247.1166 -51.9938 90)
		(property "Reference" "C442"
			(at 0 0 90)
			(layer "B.SilkS")
			(hide yes)
			(effects
				(font
					(size 1.27 1.27)
				)
				(justify mirror)
			)
		)
		(property "Value" "SCD1U16V1KX-1-GP"
			(at 2.8321 -1.7399 90)
			(unlocked yes)
			(layer "B.Fab")
			(hide yes)
			(effects
				(font
					(size 1.016 1.016)
					(thickness 0.1524)
				)
				(justify mirror)
			)
		)
		(property "Device Type" "C0201H13"
			(at 2.8321 -3.2639 90)
			(unlocked yes)
			(layer "B.Fab")
			(hide yes)
			(effects
				(font
					(size 1.016 1.016)
					(thickness 0.1524)
				)
				(justify mirror)
			)
		)
		(duplicate_pad_numbers_are_jumpers no)
		(fp_rect
			(start 0.2794 0.6477)
			(end -0.2794 -0.6477)
			(stroke
				(width 0)
				(type default)
			)
			(fill no)
			(layer "B.CrtYd")
		)
		(fp_rect
			(start 0.2794 0.6477)
			(end -0.2794 -0.6477)
			(stroke
				(width 0)
				(type default)
			)
			(fill no)
			(layer "B.Fab")
		)
		(pad "1" smd custom
			(at 0 -0.2794 270)
			(size 0.0762 0.0762)
			(layers "B.Cu" "B.Mask" "B.Paste")
			(net "DUT_VDD")
			(options
				(clearance outline)
				(anchor circle)
			)
			(primitives
				(gr_poly
					(pts
						(arc
							(start 0.1524 0.127)
							(mid 0.137521 0.162921)
							(end 0.1016 0.1778)
						)
						(arc
							(start -0.1016 0.1778)
							(mid -0.137521 0.162921)
							(end -0.1524 0.127)
						)
						(arc
							(start -0.1524 -0.127)
							(mid -0.137521 -0.162921)
							(end -0.1016 -0.1778)
						)
						(arc
							(start 0.1016 -0.1778)
							(mid 0.137521 -0.162921)
							(end 0.1524 -0.127)
						)
					)
					(width 0)
					(fill yes)
				)
			)
		)
		(pad "2" smd custom
			(at 0 0.2794 270)
			(size 0.0762 0.0762)
			(layers "B.Cu" "B.Mask" "B.Paste")
			(net "GND")
			(options
				(clearance outline)
				(anchor circle)
			)
			(primitives
				(gr_poly
					(pts
						(arc
							(start 0.1524 0.127)
							(mid 0.137521 0.162921)
							(end 0.1016 0.1778)
						)
						(arc
							(start -0.1016 0.1778)
							(mid -0.137521 0.162921)
							(end -0.1524 0.127)
						)
						(arc
							(start -0.1524 -0.127)
							(mid -0.137521 -0.162921)
							(end -0.1016 -0.1778)
						)
						(arc
							(start 0.1016 -0.1778)
							(mid 0.137521 -0.162921)
							(end 0.1524 -0.127)
						)
					)
					(width 0)
					(fill yes)
				)
			)
		)
	)
	(footprint ""
		(layer "B.Cu")
		(at 241.6048 -56.9976 -90)
		(property "Reference" "C513"
			(at 0 0 90)
			(layer "B.SilkS")
			(hide yes)
			(effects
				(font
					(size 1.27 1.27)
				)
				(justify mirror)
			)
		)
		(property "Value" "SCD1U16V1KX-1-GP"
			(at 2.8321 -1.7399 270)
			(unlocked yes)
			(layer "B.Fab")
			(hide yes)
			(effects
				(font
					(size 1.016 1.016)
					(thickness 0.1524)
				)
				(justify mirror)
			)
		)
		(property "Device Type" "C0201H13"
			(at 2.8321 -3.2639 270)
			(unlocked yes)
			(layer "B.Fab")
			(hide yes)
			(effects
				(font
					(size 1.016 1.016)
					(thickness 0.1524)
				)
				(justify mirror)
			)
		)
		(duplicate_pad_numbers_are_jumpers no)
		(fp_rect
			(start 0.2794 0.6477)
			(end -0.2794 -0.6477)
			(stroke
				(width 0)
				(type default)
			)
			(fill no)
			(layer "B.CrtYd")
		)
		(fp_rect
			(start 0.2794 0.6477)
			(end -0.2794 -0.6477)
			(stroke
				(width 0)
				(type default)
			)
			(fill no)
			(layer "B.Fab")
		)
		(pad "1" smd custom
			(at 0 -0.2794 90)
			(size 0.0762 0.0762)
			(layers "B.Cu" "B.Mask" "B.Paste")
			(net "DUT_AVD_TX")
			(options
				(clearance outline)
				(anchor circle)
			)
			(primitives
				(gr_poly
					(pts
						(arc
							(start 0.1524 0.127)
							(mid 0.137521 0.162921)
							(end 0.1016 0.1778)
						)
						(arc
							(start -0.1016 0.1778)
							(mid -0.137521 0.162921)
							(end -0.1524 0.127)
						)
						(arc
							(start -0.1524 -0.127)
							(mid -0.137521 -0.162921)
							(end -0.1016 -0.1778)
						)
						(arc
							(start 0.1016 -0.1778)
							(mid 0.137521 -0.162921)
							(end 0.1524 -0.127)
						)
					)
					(width 0)
					(fill yes)
				)
			)
		)
		(pad "2" smd custom
			(at 0 0.2794 90)
			(size 0.0762 0.0762)
			(layers "B.Cu" "B.Mask" "B.Paste")
			(net "GND")
			(options
				(clearance outline)
				(anchor circle)
			)
			(primitives
				(gr_poly
					(pts
						(arc
							(start 0.1524 0.127)
							(mid 0.137521 0.162921)
							(end 0.1016 0.1778)
						)
						(arc
							(start -0.1016 0.1778)
							(mid -0.137521 0.162921)
							(end -0.1524 0.127)
						)
						(arc
							(start -0.1524 -0.127)
							(mid -0.137521 -0.162921)
							(end -0.1016 -0.1778)
						)
						(arc
							(start 0.1016 -0.1778)
							(mid 0.137521 -0.162921)
							(end 0.1524 -0.127)
						)
					)
					(width 0)
					(fill yes)
				)
			)
		)
	)
)
